#ISCELL
  pure_quanta quanta_title_block_c *
  *
#ISCELL
  standard offpage *
  page57_i1
#ISCELL
  standard tap *
  page57_i10
#ISCELL
  standard tap *
  page57_i100
#ISCELL
  standard tap *
  page57_i101
#ISCELL
  standard tap *
  page57_i102
#ISCELL
  standard tap *
  page57_i103
#ISCELL
  standard tap *
  page57_i104
#ISCELL
  standard tap *
  page57_i105
#ISCELL
  standard tap *
  page57_i106
#ISCELL
  standard tap *
  page57_i107
#ISCELL
  standard tap *
  page57_i108
#ISCELL
  standard tap *
  page57_i109
#ISCELL
  standard tap *
  page57_i11
#ISCELL
  standard tap *
  page57_i110
#ISCELL
  standard tap *
  page57_i111
#ISCELL
  standard tap *
  page57_i112
#ISCELL
  standard tap *
  page57_i113
#ISCELL
  standard tap *
  page57_i114
#ISCELL
  standard tap *
  page57_i115
#ISCELL
  standard tap *
  page57_i116
#ISCELL
  standard tap *
  page57_i117
#ISCELL
  standard tap *
  page57_i118
#ISCELL
  standard tap *
  page57_i119
#ISCELL
  standard tap *
  page57_i12
#ISCELL
  standard tap *
  page57_i120
#ISCELL
  standard tap *
  page57_i121
#ISCELL
  standard tap *
  page57_i122
#ISCELL
  standard tap *
  page57_i123
#ISCELL
  standard tap *
  page57_i124
#ISCELL
  standard tap *
  page57_i125
#ISCELL
  standard tap *
  page57_i126
#ISCELL
  standard tap *
  page57_i127
#ISCELL
  standard tap *
  page57_i128
#ISCELL
  standard tap *
  page57_i129
#ISCELL
  standard tap *
  page57_i13
#ISCELL
  standard tap *
  page57_i130
#ISCELL
  standard tap *
  page57_i131
#ISCELL
  standard tap *
  page57_i132
#ISCELL
  standard tap *
  page57_i133
#ISCELL
  standard tap *
  page57_i134
#ISCELL
  standard tap *
  page57_i135
#ISCELL
  standard tap *
  page57_i136
#ISCELL
  standard tap *
  page57_i137
#ISCELL
  standard tap *
  page57_i138
#ISCELL
  standard tap *
  page57_i139
#ISCELL
  standard tap *
  page57_i14
#ISCELL
  standard tap *
  page57_i140
#ISCELL
  standard tap *
  page57_i141
#ISCELL
  standard tap *
  page57_i142
#ISCELL
  standard tap *
  page57_i143
#ISCELL
  standard tap *
  page57_i144
#ISCELL
  standard tap *
  page57_i145
#ISCELL
  standard tap *
  page57_i146
#ISCELL
  standard tap *
  page57_i147
#ISCELL
  standard tap *
  page57_i148
#ISCELL
  standard tap *
  page57_i149
#ISCELL
  standard tap *
  page57_i15
#ISCELL
  standard tap *
  page57_i150
#ISCELL
  standard tap *
  page57_i151
#ISCELL
  standard tap *
  page57_i152
#ISCELL
  standard tap *
  page57_i153
#ISCELL
  standard tap *
  page57_i154
#ISCELL
  standard tap *
  page57_i155
#ISCELL
  standard offpage *
  page57_i156
#ISCELL
  standard offpage *
  page57_i157
#ISCELL
  standard offpage *
  page57_i158
#ISCELL
  standard offpage *
  page57_i159
#ISCELL
  standard tap *
  page57_i16
#ISCELL
  standard offpage *
  page57_i160
#ISCELL
  standard offpage *
  page57_i161
#ISCELL
  standard offpage *
  page57_i162
#ISCELL
  standard offpage *
  page57_i163
#ISCELL
  standard offpage *
  page57_i164
#ISCELL
  standard offpage *
  page57_i165
#ISCELL
  standard offpage *
  page57_i166
#ISCELL
  standard offpage *
  page57_i167
#CELL
  pure_quanta socket4677_azif0045p001c01cs *
  page57_i168
#ISCELL
  standard tap *
  page57_i17
#ISCELL
  standard tap *
  page57_i18
#ISCELL
  standard tap *
  page57_i19
#ISCELL
  standard offpage *
  page57_i2
#ISCELL
  standard tap *
  page57_i20
#ISCELL
  standard tap *
  page57_i21
#ISCELL
  standard tap *
  page57_i22
#ISCELL
  standard tap *
  page57_i23
#ISCELL
  standard tap *
  page57_i24
#ISCELL
  standard tap *
  page57_i25
#ISCELL
  standard tap *
  page57_i26
#ISCELL
  standard tap *
  page57_i27
#ISCELL
  standard tap *
  page57_i28
#ISCELL
  standard tap *
  page57_i29
#ISCELL
  standard tap *
  page57_i3
#ISCELL
  standard tap *
  page57_i30
#ISCELL
  standard tap *
  page57_i31
#ISCELL
  standard tap *
  page57_i32
#ISCELL
  standard tap *
  page57_i33
#ISCELL
  standard tap *
  page57_i34
#ISCELL
  standard tap *
  page57_i35
#ISCELL
  standard tap *
  page57_i36
#ISCELL
  standard tap *
  page57_i37
#ISCELL
  standard tap *
  page57_i38
#ISCELL
  standard tap *
  page57_i39
#ISCELL
  standard tap *
  page57_i4
#ISCELL
  standard tap *
  page57_i40
#ISCELL
  standard tap *
  page57_i41
#ISCELL
  standard tap *
  page57_i42
#ISCELL
  standard tap *
  page57_i43
#ISCELL
  standard tap *
  page57_i44
#ISCELL
  standard tap *
  page57_i45
#ISCELL
  standard tap *
  page57_i46
#ISCELL
  standard tap *
  page57_i47
#ISCELL
  standard offpage *
  page57_i48
#ISCELL
  standard offpage *
  page57_i49
#ISCELL
  standard tap *
  page57_i5
#ISCELL
  standard tap *
  page57_i50
#ISCELL
  standard tap *
  page57_i51
#ISCELL
  standard tap *
  page57_i52
#ISCELL
  standard tap *
  page57_i53
#ISCELL
  standard tap *
  page57_i54
#ISCELL
  standard tap *
  page57_i55
#ISCELL
  standard tap *
  page57_i56
#ISCELL
  standard tap *
  page57_i57
#ISCELL
  standard tap *
  page57_i58
#ISCELL
  standard tap *
  page57_i59
#ISCELL
  standard tap *
  page57_i6
#ISCELL
  standard tap *
  page57_i60
#ISCELL
  standard tap *
  page57_i61
#ISCELL
  standard tap *
  page57_i62
#ISCELL
  standard tap *
  page57_i63
#ISCELL
  standard tap *
  page57_i64
#ISCELL
  standard tap *
  page57_i65
#ISCELL
  standard tap *
  page57_i66
#ISCELL
  standard tap *
  page57_i67
#ISCELL
  standard tap *
  page57_i68
#ISCELL
  standard tap *
  page57_i69
#ISCELL
  standard offpage *
  page57_i7
#ISCELL
  standard tap *
  page57_i70
#ISCELL
  standard tap *
  page57_i71
#ISCELL
  standard tap *
  page57_i72
#ISCELL
  standard tap *
  page57_i73
#ISCELL
  standard tap *
  page57_i74
#ISCELL
  standard tap *
  page57_i75
#ISCELL
  standard tap *
  page57_i76
#ISCELL
  standard tap *
  page57_i77
#ISCELL
  standard tap *
  page57_i78
#ISCELL
  standard tap *
  page57_i79
#ISCELL
  standard offpage *
  page57_i8
#ISCELL
  standard tap *
  page57_i80
#ISCELL
  standard tap *
  page57_i81
#ISCELL
  standard tap *
  page57_i82
#ISCELL
  standard tap *
  page57_i83
#ISCELL
  standard tap *
  page57_i84
#ISCELL
  standard tap *
  page57_i85
#ISCELL
  standard tap *
  page57_i86
#ISCELL
  standard tap *
  page57_i87
#ISCELL
  standard tap *
  page57_i88
#ISCELL
  standard tap *
  page57_i89
#ISCELL
  standard tap *
  page57_i9
#ISCELL
  standard tap *
  page57_i90
#ISCELL
  standard offpage *
  page57_i91
#ISCELL
  standard offpage *
  page57_i92
#ISCELL
  standard offpage *
  page57_i93
#ISCELL
  standard tap *
  page57_i94
#ISCELL
  standard tap *
  page57_i95
#ISCELL
  standard tap *
  page57_i96
#ISCELL
  standard tap *
  page57_i97
#ISCELL
  standard tap *
  page57_i98
#ISCELL
  standard tap *
  page57_i99
